# S9S_MB_2U (Grand Teton) — schematic netlist excerpt (pin names and nets, part order shuffled) for the footprints in the layout excerpt that follows; sources: Cadence DE-HDL packaged netlist, KiCad conversion of 03242023_DA0F0TMBIJ0_F0T_Motherboard_J_brd_V01_OCP.brd

R2967  Q_RES  0 5% CHIP  pkg 0402LF  page 231 : A = SMB_PCIE0_3V3AUX_SCL_R3 ; B = SMB_SENSOR_M2_P0_3V3AUX_SCL
C815  Q_CAP_DIFFBUS  DIFF BUS_0.22UF 6.3V 20% X6S  pkg C0201  page 175 : \1\ = P5E_CPU1_PE1_TX_C_DP<11> ; \2\ = P5E_CPU1_PE1_TX_DP<11>
R3681  Q_RES  0 5% EMPTY  pkg 0402LF  page 250 : A = P3V3_AUX_ADC ; B = P3V3_AUX_ADC_MAM

(kicad_pcb
	(version 20260206)
	(generator "pcbnew")
	(generator_version "10.0")
	(general
		(thickness 1.6)
		(legacy_teardrops no)
	)
	(paper "A4")
	(title_block
		(title "03242023_DA0F0TMBIJ0_F0T_Motherboard_J_brd_V01_OCP.brd")
		(comment 1 "Grand Teton / footprints 2160-2162 of 6105")
	)
	(layers
		(0 "F.Cu" signal "TOP")
		(4 "In1.Cu" signal "GND")
		(6 "In2.Cu" signal "IN1")
		(8 "In3.Cu" signal "GND1")
		(10 "In4.Cu" signal "IN2")
		(12 "In5.Cu" signal "GND2")
		(14 "In6.Cu" signal "IN3")
		(16 "In7.Cu" signal "GND3")
		(18 "In8.Cu" signal "VCC")
		(20 "In9.Cu" signal "VCC1")
		(22 "In10.Cu" signal "GND4")
		(24 "In11.Cu" signal "IN4")
		(26 "In12.Cu" signal "GND5")
		(28 "In13.Cu" signal "IN5")
		(30 "In14.Cu" signal "GND6")
		(32 "In15.Cu" signal "IN6")
		(34 "In16.Cu" signal "GND7")
		(2 "B.Cu" signal "BOTTOM")
		(9 "F.Adhes" user "F.Adhesive")
		(11 "B.Adhes" user "B.Adhesive")
		(13 "F.Paste" user "Package Geometry/Pastemask Top")
		(15 "B.Paste" user "Package Geometry/Pastemask Bottom")
		(5 "F.SilkS" user "Ref Des/Silkscreen Top")
		(7 "B.SilkS" user "Ref Des/Silkscreen Bottom")
		(1 "F.Mask" user "Board Geometry/Soldermask Top")
		(3 "B.Mask" user "Board Geometry/Soldermask Bottom")
		(17 "Dwgs.User" user "User.Drawings")
		(19 "Cmts.User" user "User.Comments")
		(21 "Eco1.User" user "User.Eco1")
		(23 "Eco2.User" user "User.Eco2")
		(25 "Edge.Cuts" user "Board Geometry/Outline")
		(27 "Margin" user)
		(31 "F.CrtYd" user "Package Geometry/Place Bound Top")
		(29 "B.CrtYd" user "Package Geometry/Place Bound Bottom")
		(35 "F.Fab" user "Ref Des/Assembly Top")
		(33 "B.Fab" user "Ref Des/Assembly Bottom")
	)
	(footprint ""
		(layer "F.Cu")
		(at 113.494312 -130.424682 180)
		(property "Reference" "R2967"
			(at 0 0 180)
			(layer "F.SilkS")
			(hide yes)
			(effects
				(font
					(size 1.27 1.27)
				)
			)
		)
		(property "Value" ""
			(at 0 0 180)
			(layer "F.Fab")
			(effects
				(font
					(size 1.27 1.27)
				)
			)
		)
		(duplicate_pad_numbers_are_jumpers no)
		(fp_line
			(start 0.7874 0.4064)
			(end -0.7874 0.4064)
			(stroke
				(width 0.1524)
				(type default)
			)
			(layer "F.SilkS")
		)
		(fp_line
			(start 0.7874 -0.4064)
			(end 0.7874 0.4064)
			(stroke
				(width 0.1524)
				(type default)
			)
			(layer "F.SilkS")
		)
		(fp_line
			(start -0.7874 0.4064)
			(end -0.7874 -0.4064)
			(stroke
				(width 0.1524)
				(type default)
			)
			(layer "F.SilkS")
		)
		(fp_line
			(start -0.7874 -0.4064)
			(end 0.7874 -0.4064)
			(stroke
				(width 0.1524)
				(type default)
			)
			(layer "F.SilkS")
		)
		(fp_line
			(start 0.67945 0.3048)
			(end 0.120396 0.3048)
			(stroke
				(width 0.1)
				(type default)
			)
			(layer "F.Fab")
		)
		(fp_line
			(start 0.67945 -0.3048)
			(end 0.67945 0.3048)
			(stroke
				(width 0.1)
				(type default)
			)
			(layer "F.Fab")
		)
		(fp_line
			(start 0.12065 -0.2794)
			(end 0.12065 -0.3048)
			(stroke
				(width 0.1)
				(type default)
			)
			(layer "F.Fab")
		)
		(fp_line
			(start 0.12065 -0.3048)
			(end 0.67945 -0.3048)
			(stroke
				(width 0.1)
				(type default)
			)
			(layer "F.Fab")
		)
		(fp_line
			(start 0.120396 0.3048)
			(end 0.120396 0.2794)
			(stroke
				(width 0.1)
				(type default)
			)
			(layer "F.Fab")
		)
		(fp_line
			(start 0.120396 0.2794)
			(end -0.12065 0.2794)
			(stroke
				(width 0.1)
				(type default)
			)
			(layer "F.Fab")
		)
		(fp_line
			(start -0.12065 0.3048)
			(end -0.67945 0.3048)
			(stroke
				(width 0.1)
				(type default)
			)
			(layer "F.Fab")
		)
		(fp_line
			(start -0.12065 0.2794)
			(end -0.12065 0.3048)
			(stroke
				(width 0.1)
				(type default)
			)
			(layer "F.Fab")
		)
		(fp_line
			(start -0.12065 -0.2794)
			(end 0.12065 -0.2794)
			(stroke
				(width 0.1)
				(type default)
			)
			(layer "F.Fab")
		)
		(fp_line
			(start -0.12065 -0.305054)
			(end -0.12065 -0.2794)
			(stroke
				(width 0.1)
				(type default)
			)
			(layer "F.Fab")
		)
		(fp_line
			(start -0.67945 0.3048)
			(end -0.67945 -0.305054)
			(stroke
				(width 0.1)
				(type default)
			)
			(layer "F.Fab")
		)
		(fp_line
			(start -0.67945 -0.305054)
			(end -0.12065 -0.305054)
			(stroke
				(width 0.1)
				(type default)
			)
			(layer "F.Fab")
		)
		(pad "1" smd circle
			(at -0.40005 0 180)
			(size 0 0)
			(layers "F.Cu" "F.Mask" "F.Paste")
			(net "SMB_PCIE0_3V3AUX_SCL_R3")
		)
		(pad "2" smd circle
			(at 0.40005 0 180)
			(size 0 0)
			(layers "F.Cu" "F.Mask" "F.Paste")
			(net "SMB_SENSOR_M2_P0_3V3AUX_SCL")
		)
	)
	(footprint ""
		(layer "F.Cu")
		(at 26.684478 -16.099536 90)
		(property "Reference" "C815"
			(at 0 0 90)
			(layer "F.SilkS")
			(hide yes)
			(effects
				(font
					(size 1.27 1.27)
				)
			)
		)
		(property "Value" ""
			(at 0 0 90)
			(layer "F.Fab")
			(effects
				(font
					(size 1.27 1.27)
				)
			)
		)
		(duplicate_pad_numbers_are_jumpers no)
		(fp_line
			(start 0.299974 -0.150114)
			(end 0.299974 0.150114)
			(stroke
				(width 0.1)
				(type default)
			)
			(layer "F.Fab")
		)
		(fp_line
			(start -0.299974 -0.150114)
			(end 0.299974 -0.150114)
			(stroke
				(width 0.1)
				(type default)
			)
			(layer "F.Fab")
		)
		(fp_line
			(start 0.299974 0.150114)
			(end -0.299974 0.150114)
			(stroke
				(width 0.1)
				(type default)
			)
			(layer "F.Fab")
		)
		(fp_line
			(start -0.299974 0.150114)
			(end -0.299974 -0.150114)
			(stroke
				(width 0.1)
				(type default)
			)
			(layer "F.Fab")
		)
		(pad "1" smd rect
			(at -0.2667 0 90)
			(size 0.3048 0.381)
			(layers "F.Cu" "F.Mask" "F.Paste")
			(net "P5E_CPU1_PE1_TX_C_DP<11>")
		)
		(pad "2" smd rect
			(at 0.2667 0 90)
			(size 0.3048 0.381)
			(layers "F.Cu" "F.Mask" "F.Paste")
			(net "P5E_CPU1_PE1_TX_DP<11>")
		)
	)
	(footprint ""
		(layer "F.Cu")
		(at 40.627554 -107.031282)
		(property "Reference" "R3681"
			(at 0 0 0)
			(layer "F.SilkS")
			(hide yes)
			(effects
				(font
					(size 1.27 1.27)
				)
			)
		)
		(property "Value" ""
			(at 0 0 0)
			(layer "F.Fab")
			(effects
				(font
					(size 1.27 1.27)
				)
			)
		)
		(duplicate_pad_numbers_are_jumpers no)
		(fp_line
			(start -0.7874 -0.4064)
			(end 0.7874 -0.4064)
			(stroke
				(width 0.1524)
				(type default)
			)
			(layer "F.SilkS")
		)
		(fp_line
			(start -0.7874 0.4064)
			(end -0.7874 -0.4064)
			(stroke
				(width 0.1524)
				(type default)
			)
			(layer "F.SilkS")
		)
		(fp_line
			(start 0.7874 -0.4064)
			(end 0.7874 0.4064)
			(stroke
				(width 0.1524)
				(type default)
			)
			(layer "F.SilkS")
		)
		(fp_line
			(start 0.7874 0.4064)
			(end -0.7874 0.4064)
			(stroke
				(width 0.1524)
				(type default)
			)
			(layer "F.SilkS")
		)
		(fp_line
			(start -0.67945 -0.305054)
			(end -0.12065 -0.305054)
			(stroke
				(width 0.1)
				(type default)
			)
			(layer "F.Fab")
		)
		(fp_line
			(start -0.67945 0.3048)
			(end -0.67945 -0.305054)
			(stroke
				(width 0.1)
				(type default)
			)
			(layer "F.Fab")
		)
		(fp_line
			(start -0.12065 -0.305054)
			(end -0.12065 -0.2794)
			(stroke
				(width 0.1)
				(type default)
			)
			(layer "F.Fab")
		)
		(fp_line
			(start -0.12065 -0.2794)
			(end 0.12065 -0.2794)
			(stroke
				(width 0.1)
				(type default)
			)
			(layer "F.Fab")
		)
		(fp_line
			(start -0.12065 0.2794)
			(end -0.12065 0.3048)
			(stroke
				(width 0.1)
				(type default)
			)
			(layer "F.Fab")
		)
		(fp_line
			(start -0.12065 0.3048)
			(end -0.67945 0.3048)
			(stroke
				(width 0.1)
				(type default)
			)
			(layer "F.Fab")
		)
		(fp_line
			(start 0.120396 0.2794)
			(end -0.12065 0.2794)
			(stroke
				(width 0.1)
				(type default)
			)
			(layer "F.Fab")
		)
		(fp_line
			(start 0.120396 0.3048)
			(end 0.120396 0.2794)
			(stroke
				(width 0.1)
				(type default)
			)
			(layer "F.Fab")
		)
		(fp_line
			(start 0.12065 -0.3048)
			(end 0.67945 -0.3048)
			(stroke
				(width 0.1)
				(type default)
			)
			(layer "F.Fab")
		)
		(fp_line
			(start 0.12065 -0.2794)
			(end 0.12065 -0.3048)
			(stroke
				(width 0.1)
				(type default)
			)
			(layer "F.Fab")
		)
		(fp_line
			(start 0.67945 -0.3048)
			(end 0.67945 0.3048)
			(stroke
				(width 0.1)
				(type default)
			)
			(layer "F.Fab")
		)
		(fp_line
			(start 0.67945 0.3048)
			(end 0.120396 0.3048)
			(stroke
				(width 0.1)
				(type default)
			)
			(layer "F.Fab")
		)
		(pad "1" smd rect
			(at -0.40005 0 180)
			(size 0.4572 0.508)
			(layers "F.Cu" "F.Mask" "F.Paste")
			(net "P3V3_AUX_ADC")
		)
		(pad "2" smd rect
			(at 0.40005 0 180)
			(size 0.4572 0.508)
			(layers "F.Cu" "F.Mask" "F.Paste")
			(net "P3V3_AUX_ADC_MAM")
		)
	)
)
